(kicad_pcb
	(version 20241229)
	(generator "pcbnew")
	(generator_version "9.0")
	(general
		(thickness 1.599998)
		(legacy_teardrops no)
	)
	(paper "A4")
	(title_block
		(date "2023-02-12")
		(rev "1.1.5")
		(comment 9 "footprints 24-28 of 473")
	)
	(layers
		(0 "F.Cu" signal)
		(4 "In1.Cu" power "In1.GND")
		(6 "In2.Cu" signal)
		(8 "In3.Cu" power "In3.GND")
		(10 "In4.Cu" power "In4.VCC")
		(12 "In5.Cu" signal)
		(14 "In6.Cu" power "In6.VCC")
		(2 "B.Cu" signal)
		(9 "F.Adhes" user "F.Adhesive")
		(11 "B.Adhes" user "B.Adhesive")
		(13 "F.Paste" user)
		(15 "B.Paste" user)
		(5 "F.SilkS" user "F.Silkscreen")
		(7 "B.SilkS" user "B.Silkscreen")
		(1 "F.Mask" user)
		(3 "B.Mask" user)
		(17 "Dwgs.User" user "User.Drawings")
		(19 "Cmts.User" user "User.Comments")
		(21 "Eco1.User" user "User.Eco1")
		(23 "Eco2.User" user "User.Eco2")
		(25 "Edge.Cuts" user)
		(27 "Margin" user)
		(31 "F.CrtYd" user "F.Courtyard")
		(29 "B.CrtYd" user "B.Courtyard")
		(35 "F.Fab" user)
		(33 "B.Fab" user)
	)
	(footprint "antmicro-footprints:L_WE-PDF-1064"
		(layer "F.Cu")
		(at 126.860528 115.747157 90)
		(property "Reference" "L1"
			(at -6.252843 4.139472 0)
			(layer "F.SilkS")
			(effects
				(font
					(size 0.7 0.7)
					(thickness 0.15)
				)
				(justify left bottom)
			)
		)
		(property "Value" "L_7u2_7.9A_WE-PDF"
			(at 0 6.6 270)
			(layer "F.Fab")
			(effects
				(font
					(size 0.7 0.7)
					(thickness 0.15)
				)
				(justify left bottom)
			)
		)
		(property "Author" "Antmicro"
			(at 242.607685 -11.113371 0)
			(layer "F.Fab")
			(hide yes)
			(effects
				(font
					(size 1 1)
					(thickness 0.15)
				)
			)
		)
		(property "IMax" ""
			(at 242.607685 -11.113371 0)
			(layer "F.Fab")
			(hide yes)
			(effects
				(font
					(size 1 1)
					(thickness 0.15)
				)
			)
		)
		(property "ISat" ""
			(at 242.607685 -11.113371 0)
			(layer "F.Fab")
			(hide yes)
			(effects
				(font
					(size 1 1)
					(thickness 0.15)
				)
			)
		)
		(property "License" "Apache-2.0"
			(at 242.607685 -11.113371 0)
			(layer "F.Fab")
			(hide yes)
			(effects
				(font
					(size 1 1)
					(thickness 0.15)
				)
			)
		)
		(property "MPN" "7447798720"
			(at 242.607685 -11.113371 0)
			(layer "F.Fab")
			(hide yes)
			(effects
				(font
					(size 1 1)
					(thickness 0.15)
				)
			)
		)
		(property "Manufacturer" "Würth Elektronik"
			(at 242.607685 -11.113371 0)
			(layer "F.Fab")
			(hide yes)
			(effects
				(font
					(size 1 1)
					(thickness 0.15)
				)
			)
		)
		(property "Size" "10.2x10.2"
			(at 242.607685 -11.113371 0)
			(layer "F.Fab")
			(hide yes)
			(effects
				(font
					(size 1 1)
					(thickness 0.15)
				)
			)
		)
		(property "Val" "7u2/7.9A"
			(at 242.607685 -11.113371 0)
			(layer "F.Fab")
			(hide yes)
			(effects
				(font
					(size 1 1)
					(thickness 0.15)
				)
			)
		)
		(sheetname "Supply")
		(sheetfile "supply.kicad_sch")
		(attr smd)
		(fp_line
			(start 4.099 -5.202)
			(end 5.2 -4.1)
			(stroke
				(width 0.15)
				(type solid)
			)
			(layer "F.SilkS")
		)
		(fp_line
			(start -5.202 -5.202)
			(end 4.099 -5.202)
			(stroke
				(width 0.15)
				(type solid)
			)
			(layer "F.SilkS")
		)
		(fp_line
			(start 5.2 -4.1)
			(end 5.2 -2)
			(stroke
				(width 0.15)
				(type solid)
			)
			(layer "F.SilkS")
		)
		(fp_line
			(start -5.202 -2)
			(end -5.202 -5.202)
			(stroke
				(width 0.15)
				(type solid)
			)
			(layer "F.SilkS")
		)
		(fp_line
			(start 5.2 1.999)
			(end 5.2 4.2)
			(stroke
				(width 0.15)
				(type solid)
			)
			(layer "F.SilkS")
		)
		(fp_line
			(start 5.2 4.2)
			(end 5.2 5.2)
			(stroke
				(width 0.15)
				(type solid)
			)
			(layer "F.SilkS")
		)
		(fp_line
			(start 5.2 5.2)
			(end -5.202 5.2)
			(stroke
				(width 0.15)
				(type solid)
			)
			(layer "F.SilkS")
		)
		(fp_line
			(start -5.202 5.2)
			(end -5.202 1.999)
			(stroke
				(width 0.15)
				(type solid)
			)
			(layer "F.SilkS")
		)
		(fp_rect
			(start -5.601 -5.601)
			(end 5.599 5.599)
			(stroke
				(width 0.05)
				(type solid)
			)
			(fill no)
			(layer "F.CrtYd")
		)
		(pad "1" smd rect
			(at -4.1 0 180)
			(size 3.4 2.4)
			(layers "F.Cu" "F.Mask" "F.Paste")
			(net 42 "Net-(IC2-SW)")
			(pintype "passive")
		)
		(pad "2" smd rect
			(at 4.099 0 180)
			(size 3.4 2.4)
			(layers "F.Cu" "F.Mask" "F.Paste")
			(net 55 "Net-(C141-Pad1)")
			(pintype "passive")
		)
	)
	(footprint "antmicro-footprints:WSON-10-1EP_4x4mm_P0.8mm_EP2.6x3mm"
		(layer "F.Cu")
		(at 114.235528 116.297157)
		(property "Reference" "IC2"
			(at -2.635528 -0.497157 270)
			(layer "F.SilkS")
			(effects
				(font
					(size 0.7 0.7)
					(thickness 0.15)
				)
				(justify left bottom)
			)
		)
		(property "Value" "TPS54561QDPRRQ1"
			(at 0 3.4 180)
			(layer "F.Fab")
			(effects
				(font
					(size 0.7 0.7)
					(thickness 0.15)
				)
				(justify left bottom)
			)
		)
		(property "Description" " 4.5-V to 60-V Input, 5-A, Step-Down DC-DC Converter"
			(at 0 0 0)
			(layer "F.Fab")
			(hide yes)
			(effects
				(font
					(size 1.27 1.27)
					(thickness 0.15)
				)
			)
		)
		(property "Author" "Antmicro"
			(at 0 0 0)
			(layer "F.Fab")
			(hide yes)
			(effects
				(font
					(size 1 1)
					(thickness 0.15)
				)
			)
		)
		(property "License" "Apache-2.0"
			(at 0 0 0)
			(layer "F.Fab")
			(hide yes)
			(effects
				(font
					(size 1 1)
					(thickness 0.15)
				)
			)
		)
		(property "MPN" "TPS54561QDPRRQ1"
			(at 0 0 0)
			(layer "F.Fab")
			(hide yes)
			(effects
				(font
					(size 1 1)
					(thickness 0.15)
				)
			)
		)
		(property "Manufacturer" "Texas Instruments"
			(at 0 0 0)
			(layer "F.Fab")
			(hide yes)
			(effects
				(font
					(size 1 1)
					(thickness 0.15)
				)
			)
		)
		(sheetname "Supply")
		(sheetfile "supply.kicad_sch")
		(attr smd)
		(fp_line
			(start -2.1 -2.123)
			(end -2.1 -1.877)
			(stroke
				(width 0.15)
				(type solid)
			)
			(layer "F.SilkS")
		)
		(fp_line
			(start -2.1 -2.123)
			(end 2.1 -2.123)
			(stroke
				(width 0.15)
				(type solid)
			)
			(layer "F.SilkS")
		)
		(fp_line
			(start -2.1 2.096)
			(end -2.1 1.85)
			(stroke
				(width 0.15)
				(type solid)
			)
			(layer "F.SilkS")
		)
		(fp_line
			(start 2.1 -2.123)
			(end 2.1 -1.877)
			(stroke
				(width 0.15)
				(type solid)
			)
			(layer "F.SilkS")
		)
		(fp_line
			(start 2.1 2.122)
			(end -2.1 2.122)
			(stroke
				(width 0.15)
				(type solid)
			)
			(layer "F.SilkS")
		)
		(fp_line
			(start 2.1 2.122)
			(end 2.1 1.876)
			(stroke
				(width 0.15)
				(type solid)
			)
			(layer "F.SilkS")
		)
		(fp_circle
			(center -2.4 -2)
			(end -2.35 -2)
			(stroke
				(width 0.15)
				(type solid)
			)
			(fill yes)
			(layer "F.SilkS")
		)
		(fp_rect
			(start -2.57 -2.2)
			(end 2.469 2.2)
			(stroke
				(width 0.05)
				(type solid)
			)
			(fill no)
			(layer "F.CrtYd")
		)
		(fp_line
			(start -1.7 -2)
			(end -2 -1.7)
			(stroke
				(width 0.15)
				(type solid)
			)
			(layer "F.Fab")
		)
		(fp_rect
			(start -2.02 -2)
			(end 2.02 2)
			(stroke
				(width 0.15)
				(type solid)
			)
			(fill no)
			(layer "F.Fab")
		)
		(pad "1" smd roundrect
			(at -2.039 -1.603 90)
			(size 0.356 0.85)
			(layers "F.Cu" "F.Mask" "F.Paste")
			(roundrect_rratio 0.25)
			(net 43 "Net-(IC2-BOOT)")
			(pinfunction "BOOT")
			(pintype "passive")
		)
		(pad "2" smd roundrect
			(at -2.039 -0.804 90)
			(size 0.356 0.85)
			(layers "F.Cu" "F.Mask" "F.Paste")
			(roundrect_rratio 0.25)
			(net 224 "VIN")
			(pinfunction "VDD")
			(pintype "passive")
		)
		(pad "3" smd roundrect
			(at -2.039 -0.003 90)
			(size 0.356 0.85)
			(layers "F.Cu" "F.Mask" "F.Paste")
			(roundrect_rratio 0.25)
			(net 514 "/Supply/SYS_EN")
			(pinfunction "EN")
			(pintype "passive")
		)
		(pad "4" smd roundrect
			(at -2.039 0.797 90)
			(size 0.356 0.85)
			(layers "F.Cu" "F.Mask" "F.Paste")
			(roundrect_rratio 0.25)
			(net 39 "Net-(IC2-SS{slash}TR)")
			(pinfunction "SS/TR")
			(pintype "passive")
		)
		(pad "5" smd roundrect
			(at -2.039 1.596 90)
			(size 0.356 0.85)
			(layers "F.Cu" "F.Mask" "F.Paste")
			(roundrect_rratio 0.25)
			(net 77 "Net-(IC2-RT{slash}CLK)")
			(pinfunction "RT/CLK")
			(pintype "passive")
		)
		(pad "6" smd roundrect
			(at 1.961 1.596 90)
			(size 0.356 0.85)
			(layers "F.Cu" "F.Mask" "F.Paste")
			(roundrect_rratio 0.25)
			(net 660 "/Supply/5V0_FB")
			(pinfunction "FB")
			(pintype "passive")
		)
		(pad "7" smd roundrect
			(at 1.961 0.797 90)
			(size 0.356 0.85)
			(layers "F.Cu" "F.Mask" "F.Paste")
			(roundrect_rratio 0.25)
			(net 40 "Net-(IC2-COMP)")
			(pinfunction "COMP")
			(pintype "passive")
		)
		(pad "8" smd roundrect
			(at 1.961 -0.003 90)
			(size 0.356 0.85)
			(layers "F.Cu" "F.Mask" "F.Paste")
			(roundrect_rratio 0.25)
			(net 5 "GND")
			(pinfunction "GND")
			(pintype "power_in")
		)
		(pad "9" smd roundrect
			(at 1.961 -0.804 90)
			(size 0.356 0.85)
			(layers "F.Cu" "F.Mask" "F.Paste")
			(roundrect_rratio 0.25)
			(net 42 "Net-(IC2-SW)")
			(pinfunction "SW")
			(pintype "passive")
		)
		(pad "10" smd roundrect
			(at 1.961 -1.603 90)
			(size 0.356 0.85)
			(layers "F.Cu" "F.Mask" "F.Paste")
			(roundrect_rratio 0.25)
			(net 466 "SYS_ON")
			(pinfunction "PWRGD")
			(pintype "passive")
		)
		(pad "11" smd roundrect
			(at -0.038 -0.003 180)
			(size 2.6 3)
			(layers "F.Cu" "F.Mask" "F.Paste")
			(roundrect_rratio 0.05)
			(net 5 "GND")
			(pinfunction "GND")
			(pintype "passive")
		)
	)
	(footprint "antmicro-footprints:BarrelJack_Pin2mm_MJ-179PH"
		(layer "F.Cu")
		(at 118.4 122.45 -90)
		(property "Reference" "J6"
			(at -4.862 -0.784 90)
			(layer "F.SilkS")
			(effects
				(font
					(size 0.7 0.7)
					(thickness 0.15)
				)
				(justify right top)
			)
		)
		(property "Value" "BarrelJack_3167288"
			(at 0 15.4 90)
			(layer "F.Fab")
			(effects
				(font
					(size 0.7 0.7)
					(thickness 0.15)
				)
				(justify right top)
			)
		)
		(property "Description" "DC Power Connector, Jack, 4 A, 1.95 mm, PCB Mount, Through Hole"
			(at 0 0 90)
			(layer "F.Fab")
			(hide yes)
			(effects
				(font
					(size 1.27 1.27)
					(thickness 0.15)
				)
			)
		)
		(property "Author" "Antmicro"
			(at 0 0 90)
			(layer "F.Fab")
			(hide yes)
			(effects
				(font
					(size 1 1)
					(thickness 0.15)
				)
			)
		)
		(property "License" "Apache-2.0"
			(at 0 0 90)
			(layer "F.Fab")
			(hide yes)
			(effects
				(font
					(size 1 1)
					(thickness 0.15)
				)
			)
		)
		(property "MPN" "MJ-179PH"
			(at 0 0 90)
			(layer "F.Fab")
			(hide yes)
			(effects
				(font
					(size 1 1)
					(thickness 0.15)
				)
			)
		)
		(property "Manufacturer" "Multicomp Pro"
			(at 0 0 90)
			(layer "F.Fab")
			(hide yes)
			(effects
				(font
					(size 1 1)
					(thickness 0.15)
				)
			)
		)
		(sheetname "Supply")
		(sheetfile "supply.kicad_sch")
		(attr through_hole)
		(fp_line
			(start -0.1 4.8)
			(end -0.1 2.4)
			(stroke
				(width 0.15)
				(type solid)
			)
			(layer "F.SilkS")
		)
		(fp_line
			(start 10.1 4.8)
			(end 10.1 -4.8)
			(stroke
				(width 0.15)
				(type solid)
			)
			(layer "F.SilkS")
		)
		(fp_line
			(start 14 4.8)
			(end -0.1 4.8)
			(stroke
				(width 0.15)
				(type solid)
			)
			(layer "F.SilkS")
		)
		(fp_line
			(start 14 4.8)
			(end 14 -4.8)
			(stroke
				(width 0.15)
				(type solid)
			)
			(layer "F.SilkS")
		)
		(fp_line
			(start -0.1 -2.4)
			(end -0.1 -4.8)
			(stroke
				(width 0.15)
				(type solid)
			)
			(layer "F.SilkS")
		)
		(fp_line
			(start -0.1 -4.8)
			(end 0.8255 -4.8)
			(stroke
				(width 0.15)
				(type solid)
			)
			(layer "F.SilkS")
		)
		(fp_line
			(start 14 -4.8)
			(end 5.1 -4.8)
			(stroke
				(width 0.15)
				(type solid)
			)
			(layer "F.SilkS")
		)
		(fp_line
			(start -0.4 5.1)
			(end 14.3 5.1)
			(stroke
				(width 0.05)
				(type solid)
			)
			(layer "F.CrtYd")
		)
		(fp_line
			(start 14.3 5.1)
			(end 14.3 -5.1)
			(stroke
				(width 0.05)
				(type solid)
			)
			(layer "F.CrtYd")
		)
		(fp_line
			(start -1.3 2.5)
			(end -0.4 2.5)
			(stroke
				(width 0.05)
				(type solid)
			)
			(layer "F.CrtYd")
		)
		(fp_line
			(start -0.4 2.5)
			(end -0.4 5.1)
			(stroke
				(width 0.05)
				(type solid)
			)
			(layer "F.CrtYd")
		)
		(fp_line
			(start -1.3 -2.5)
			(end -1.3 2.5)
			(stroke
				(width 0.05)
				(type solid)
			)
			(layer "F.CrtYd")
		)
		(fp_line
			(start -0.4 -2.5)
			(end -1.3 -2.5)
			(stroke
				(width 0.05)
				(type solid)
			)
			(layer "F.CrtYd")
		)
		(fp_line
			(start -0.4 -5.1)
			(end -0.4 -2.5)
			(stroke
				(width 0.05)
				(type solid)
			)
			(layer "F.CrtYd")
		)
		(fp_line
			(start 0.7 -5.1)
			(end -0.4 -5.1)
			(stroke
				(width 0.05)
				(type solid)
			)
			(layer "F.CrtYd")
		)
		(fp_line
			(start 5.2 -5.1)
			(end 5.2 -6.1)
			(stroke
				(width 0.05)
				(type solid)
			)
			(layer "F.CrtYd")
		)
		(fp_line
			(start 14.3 -5.1)
			(end 5.2 -5.1)
			(stroke
				(width 0.05)
				(type solid)
			)
			(layer "F.CrtYd")
		)
		(fp_line
			(start 0.7 -6.1)
			(end 0.7 -5.1)
			(stroke
				(width 0.05)
				(type solid)
			)
			(layer "F.CrtYd")
		)
		(fp_line
			(start 5.2 -6.1)
			(end 0.7 -6.1)
			(stroke
				(width 0.05)
				(type solid)
			)
			(layer "F.CrtYd")
		)
		(fp_line
			(start -0.4 3.6)
			(end 0.5 4.5)
			(stroke
				(width 0.15)
				(type solid)
			)
			(layer "F.Fab")
		)
		(fp_rect
			(start -0.4 4.5)
			(end 13.7 -5.111)
			(stroke
				(width 0.15)
				(type solid)
			)
			(fill no)
			(layer "F.Fab")
		)
		(fp_text user "Author: Antmicro"
			(at -5.1 17.601 90)
			(layer "F.Fab")
			(effects
				(font
					(size 0.7 0.7)
					(thickness 0.15)
				)
				(justify right top)
			)
		)
		(fp_text user "License: Apache-2.0"
			(at -5.1 18.802 90)
			(layer "F.Fab")
			(effects
				(font
					(size 0.7 0.7)
					(thickness 0.15)
				)
				(justify right top)
			)
		)
		(fp_text user "${REFERENCE}"
			(at -5.1 16.4 90)
			(layer "F.Fab")
			(effects
				(font
					(size 0.7 0.7)
					(thickness 0.15)
				)
				(justify right top)
			)
		)
		(pad "1" thru_hole oval
			(at 0 0 270)
			(size 2 4.5)
			(drill oval 1 3.5)
			(layers "*.Cu" "*.Mask")
			(remove_unused_layers no)
			(net 76 "Net-(J6-Pad1)")
			(pinfunction "1")
			(pintype "passive")
		)
		(pad "2" thru_hole oval
			(at 2.948 -4.879 180)
			(size 1.99 4)
			(drill oval 1 3)
			(layers "*.Cu" "*.Mask")
			(remove_unused_layers no)
			(net 5 "GND")
			(pinfunction "2")
			(pintype "passive")
		)
		(pad "3" thru_hole oval
			(at 5.999 0 90)
			(size 2 4)
			(drill oval 1 3)
			(layers "*.Cu" "*.Mask")
			(remove_unused_layers no)
			(net 5 "GND")
			(pinfunction "3")
			(pintype "passive")
		)
	)
	(footprint "antmicro-footprints:C_0402_1005Metric"
		(layer "F.Cu")
		(at 117.387872 117.475 90)
		(descr "Capacitor SMD 0402")
		(tags "capacitor SMD 0402")
		(property "Reference" "C131"
			(at 1.975 0.412128 180)
			(layer "F.SilkS")
			(effects
				(font
					(size 0.7 0.7)
					(thickness 0.15)
				)
				(justify left bottom)
			)
		)
		(property "Value" "C_47p_0402"
			(at 0 1.4 90)
			(layer "F.Fab")
			(effects
				(font
					(size 0.7 0.7)
					(thickness 0.15)
				)
				(justify left bottom)
			)
		)
		(property "Description" " "
			(at 0 0 90)
			(layer "F.Fab")
			(hide yes)
			(effects
				(font
					(size 1.27 1.27)
					(thickness 0.15)
				)
			)
		)
		(property "Author" "Antmicro"
			(at 234.862872 0.087128 0)
			(layer "F.Fab")
			(hide yes)
			(effects
				(font
					(size 1 1)
					(thickness 0.15)
				)
			)
		)
		(property "Dielectric" "C0G"
			(at 234.862872 0.087128 0)
			(layer "F.Fab")
			(hide yes)
			(effects
				(font
					(size 1 1)
					(thickness 0.15)
				)
			)
		)
		(property "License" "Apache-2.0"
			(at 234.862872 0.087128 0)
			(layer "F.Fab")
			(hide yes)
			(effects
				(font
					(size 1 1)
					(thickness 0.15)
				)
			)
		)
		(property "MPN" "GRM1555C1E470JA01D"
			(at 234.862872 0.087128 0)
			(layer "F.Fab")
			(hide yes)
			(effects
				(font
					(size 1 1)
					(thickness 0.15)
				)
			)
		)
		(property "Manufacturer" "Murata"
			(at 234.862872 0.087128 0)
			(layer "F.Fab")
			(hide yes)
			(effects
				(font
					(size 1 1)
					(thickness 0.15)
				)
			)
		)
		(property "Val" "47p"
			(at 234.862872 0.087128 0)
			(layer "F.Fab")
			(hide yes)
			(effects
				(font
					(size 1 1)
					(thickness 0.15)
				)
			)
		)
		(property "Voltage" ""
			(at 234.862872 0.087128 0)
			(layer "F.Fab")
			(hide yes)
			(effects
				(font
					(size 1 1)
					(thickness 0.15)
				)
			)
		)
		(sheetname "Supply")
		(sheetfile "supply.kicad_sch")
		(attr smd)
		(fp_rect
			(start -0.94 -0.47)
			(end 0.94 0.47)
			(stroke
				(width 0.05)
				(type solid)
			)
			(fill no)
			(layer "F.CrtYd")
		)
		(fp_rect
			(start -0.499 -0.249)
			(end 0.499 0.249)
			(stroke
				(width 0.15)
				(type solid)
			)
			(fill no)
			(layer "F.Fab")
		)
		(pad "1" smd roundrect
			(at -0.484 0 90)
			(size 0.59 0.64)
			(layers "F.Cu" "F.Mask" "F.Paste")
			(roundrect_rratio 0.25)
			(net 40 "Net-(IC2-COMP)")
			(pintype "passive")
		)
		(pad "2" smd roundrect
			(at 0.484 0 90)
			(size 0.59 0.64)
			(layers "F.Cu" "F.Mask" "F.Paste")
			(roundrect_rratio 0.25)
			(net 5 "GND")
			(pintype "passive")
		)
	)
	(footprint "antmicro-footprints:TP_SMD_1mm"
		(layer "F.Cu")
		(at 109.65 119.35 90)
		(property "Reference" "TP9"
			(at -0.15 0.35 180)
			(layer "F.SilkS")
			(effects
				(font
					(size 0.7 0.7)
					(thickness 0.15)
				)
				(justify left bottom)
			)
		)
		(property "Value" "TP_1mm_SMD"
			(at 0 1.4 90)
			(layer "F.Fab")
			(effects
				(font
					(size 0.7 0.7)
					(thickness 0.15)
				)
				(justify left bottom)
			)
		)
		(property "Description" "Test Point 1mm"
			(at 0 0 90)
			(layer "F.Fab")
			(hide yes)
			(effects
				(font
					(size 1.27 1.27)
					(thickness 0.15)
				)
			)
		)
		(property "Author" "Antmicro"
			(at 229 9.7 0)
			(layer "F.Fab")
			(hide yes)
			(effects
				(font
					(size 1 1)
					(thickness 0.15)
				)
			)
		)
		(property "License" "Apache-2.0"
			(at 229 9.7 0)
			(layer "F.Fab")
			(hide yes)
			(effects
				(font
					(size 1 1)
					(thickness 0.15)
				)
			)
		)
		(property "MPN" ""
			(at 229 9.7 0)
			(layer "F.Fab")
			(hide yes)
			(effects
				(font
					(size 1 1)
					(thickness 0.15)
				)
			)
		)
		(property "Manufacturer" ""
			(at 229 9.7 0)
			(layer "F.Fab")
			(hide yes)
			(effects
				(font
					(size 1 1)
					(thickness 0.15)
				)
			)
		)
		(sheetname "Supply")
		(sheetfile "supply.kicad_sch")
		(attr exclude_from_pos_files)
		(pad "1" smd circle
			(at 0 0 90)
			(size 1 1)
			(layers "F.Cu" "F.Mask")
			(net 514 "/Supply/SYS_EN")
			(pinfunction "1")
			(pintype "passive")
		)
	)
)
